# T6G (Grand Teton) — schematic netlist excerpt (pin names and nets, part order shuffled) for the footprints in the layout excerpt that follows; sources: Cadence DE-HDL packaged netlist, KiCad conversion of 04192023_DAF0TMB3IC0_F0TG_MB_C_brd_V02_OCP.brd

PR232  Q_RES  1K 1% CHIP  pkg 0402LF  page 217 : A = P3V3_AUX ; B = PVDDIO_P1_EN_G
R6148  Q_RES  1K 1% EMPTY  pkg 0402LF  page 84 : A = P1V8_AUX ; B = FAB_BMC_REV_ID0

(kicad_pcb
	(version 20260206)
	(generator "pcbnew")
	(generator_version "10.0")
	(general
		(thickness 1.6)
		(legacy_teardrops no)
	)
	(paper "A4")
	(title_block
		(title "04192023_DAF0TMB3IC0_F0TG_MB_C_brd_V02_OCP.brd")
		(comment 1 "Grand Teton / footprints 1937-1938 of 8354")
	)
	(layers
		(0 "F.Cu" signal "TOP")
		(4 "In1.Cu" signal "GND")
		(6 "In2.Cu" signal "IN1")
		(8 "In3.Cu" signal "GND1")
		(10 "In4.Cu" signal "IN2")
		(12 "In5.Cu" signal "GND2")
		(14 "In6.Cu" signal "IN3")
		(16 "In7.Cu" signal "GND3")
		(18 "In8.Cu" signal "VCC")
		(20 "In9.Cu" signal "VCC1")
		(22 "In10.Cu" signal "GND4")
		(24 "In11.Cu" signal "IN4")
		(26 "In12.Cu" signal "GND5")
		(28 "In13.Cu" signal "IN5")
		(30 "In14.Cu" signal "GND6")
		(32 "In15.Cu" signal "IN6")
		(34 "In16.Cu" signal "GND7")
		(2 "B.Cu" signal "BOTTOM")
		(9 "F.Adhes" user "F.Adhesive")
		(11 "B.Adhes" user "B.Adhesive")
		(13 "F.Paste" user "Package Geometry/Pastemask Top")
		(15 "B.Paste" user "Package Geometry/Pastemask Bottom")
		(5 "F.SilkS" user "Ref Des/Silkscreen Top")
		(7 "B.SilkS" user "Ref Des/Silkscreen Bottom")
		(1 "F.Mask" user "Board Geometry/Soldermask Top")
		(3 "B.Mask" user "Board Geometry/Soldermask Bottom")
		(17 "Dwgs.User" user "User.Drawings")
		(19 "Cmts.User" user "User.Comments")
		(21 "Eco1.User" user "User.Eco1")
		(23 "Eco2.User" user "User.Eco2")
		(25 "Edge.Cuts" user "Board Geometry/Outline")
		(27 "Margin" user)
		(31 "F.CrtYd" user "Package Geometry/Place Bound Top")
		(29 "B.CrtYd" user "Package Geometry/Place Bound Bottom")
		(35 "F.Fab" user "Ref Des/Assembly Top")
		(33 "B.Fab" user "Ref Des/Assembly Bottom")
	)
	(footprint ""
		(layer "F.Cu")
		(at 19.05 -364.236 180)
		(property "Reference" "PR232"
			(at 0 0 180)
			(layer "F.SilkS")
			(hide yes)
			(effects
				(font
					(size 1.27 1.27)
				)
			)
		)
		(property "Value" ""
			(at 0 0 180)
			(layer "F.Fab")
			(effects
				(font
					(size 1.27 1.27)
				)
			)
		)
		(duplicate_pad_numbers_are_jumpers no)
		(fp_line
			(start 0.7874 0.4064)
			(end -0.7874 0.4064)
			(stroke
				(width 0.1524)
				(type default)
			)
			(layer "F.SilkS")
		)
		(fp_line
			(start 0.7874 -0.4064)
			(end 0.7874 0.4064)
			(stroke
				(width 0.1524)
				(type default)
			)
			(layer "F.SilkS")
		)
		(fp_line
			(start -0.7874 0.4064)
			(end -0.7874 -0.4064)
			(stroke
				(width 0.1524)
				(type default)
			)
			(layer "F.SilkS")
		)
		(fp_line
			(start -0.7874 -0.4064)
			(end 0.7874 -0.4064)
			(stroke
				(width 0.1524)
				(type default)
			)
			(layer "F.SilkS")
		)
		(fp_line
			(start 0.67945 0.3048)
			(end 0.120396 0.3048)
			(stroke
				(width 0.1)
				(type default)
			)
			(layer "F.Fab")
		)
		(fp_line
			(start 0.67945 -0.3048)
			(end 0.67945 0.3048)
			(stroke
				(width 0.1)
				(type default)
			)
			(layer "F.Fab")
		)
		(fp_line
			(start 0.12065 -0.2794)
			(end 0.12065 -0.3048)
			(stroke
				(width 0.1)
				(type default)
			)
			(layer "F.Fab")
		)
		(fp_line
			(start 0.12065 -0.3048)
			(end 0.67945 -0.3048)
			(stroke
				(width 0.1)
				(type default)
			)
			(layer "F.Fab")
		)
		(fp_line
			(start 0.120396 0.3048)
			(end 0.120396 0.2794)
			(stroke
				(width 0.1)
				(type default)
			)
			(layer "F.Fab")
		)
		(fp_line
			(start 0.120396 0.2794)
			(end -0.12065 0.2794)
			(stroke
				(width 0.1)
				(type default)
			)
			(layer "F.Fab")
		)
		(fp_line
			(start -0.12065 0.3048)
			(end -0.67945 0.3048)
			(stroke
				(width 0.1)
				(type default)
			)
			(layer "F.Fab")
		)
		(fp_line
			(start -0.12065 0.2794)
			(end -0.12065 0.3048)
			(stroke
				(width 0.1)
				(type default)
			)
			(layer "F.Fab")
		)
		(fp_line
			(start -0.12065 -0.2794)
			(end 0.12065 -0.2794)
			(stroke
				(width 0.1)
				(type default)
			)
			(layer "F.Fab")
		)
		(fp_line
			(start -0.12065 -0.305054)
			(end -0.12065 -0.2794)
			(stroke
				(width 0.1)
				(type default)
			)
			(layer "F.Fab")
		)
		(fp_line
			(start -0.67945 0.3048)
			(end -0.67945 -0.305054)
			(stroke
				(width 0.1)
				(type default)
			)
			(layer "F.Fab")
		)
		(fp_line
			(start -0.67945 -0.305054)
			(end -0.12065 -0.305054)
			(stroke
				(width 0.1)
				(type default)
			)
			(layer "F.Fab")
		)
		(pad "1" smd circle
			(at -0.40005 0 180)
			(size 0 0)
			(layers "F.Cu" "F.Mask" "F.Paste")
			(net "P3V3_AUX")
		)
		(pad "2" smd circle
			(at 0.40005 0 180)
			(size 0 0)
			(layers "F.Cu" "F.Mask" "F.Paste")
			(net "PVDDIO_P1_EN_G")
		)
	)
	(footprint ""
		(layer "F.Cu")
		(at 181.71033 -92.672408 90)
		(property "Reference" "R6148"
			(at 0 0 90)
			(layer "F.SilkS")
			(hide yes)
			(effects
				(font
					(size 1.27 1.27)
				)
			)
		)
		(property "Value" ""
			(at 0 0 90)
			(layer "F.Fab")
			(effects
				(font
					(size 1.27 1.27)
				)
			)
		)
		(duplicate_pad_numbers_are_jumpers no)
		(fp_line
			(start 0.7874 -0.4064)
			(end 0.7874 0.4064)
			(stroke
				(width 0.1524)
				(type default)
			)
			(layer "F.SilkS")
		)
		(fp_line
			(start -0.7874 -0.4064)
			(end 0.7874 -0.4064)
			(stroke
				(width 0.1524)
				(type default)
			)
			(layer "F.SilkS")
		)
		(fp_line
			(start 0.7874 0.4064)
			(end -0.7874 0.4064)
			(stroke
				(width 0.1524)
				(type default)
			)
			(layer "F.SilkS")
		)
		(fp_line
			(start -0.7874 0.4064)
			(end -0.7874 -0.4064)
			(stroke
				(width 0.1524)
				(type default)
			)
			(layer "F.SilkS")
		)
		(fp_line
			(start -0.12065 -0.305054)
			(end -0.12065 -0.2794)
			(stroke
				(width 0.1)
				(type default)
			)
			(layer "F.Fab")
		)
		(fp_line
			(start -0.67945 -0.305054)
			(end -0.12065 -0.305054)
			(stroke
				(width 0.1)
				(type default)
			)
			(layer "F.Fab")
		)
		(fp_line
			(start 0.67945 -0.3048)
			(end 0.67945 0.3048)
			(stroke
				(width 0.1)
				(type default)
			)
			(layer "F.Fab")
		)
		(fp_line
			(start 0.12065 -0.3048)
			(end 0.67945 -0.3048)
			(stroke
				(width 0.1)
				(type default)
			)
			(layer "F.Fab")
		)
		(fp_line
			(start 0.12065 -0.2794)
			(end 0.12065 -0.3048)
			(stroke
				(width 0.1)
				(type default)
			)
			(layer "F.Fab")
		)
		(fp_line
			(start -0.12065 -0.2794)
			(end 0.12065 -0.2794)
			(stroke
				(width 0.1)
				(type default)
			)
			(layer "F.Fab")
		)
		(fp_line
			(start 0.120396 0.2794)
			(end -0.12065 0.2794)
			(stroke
				(width 0.1)
				(type default)
			)
			(layer "F.Fab")
		)
		(fp_line
			(start -0.12065 0.2794)
			(end -0.12065 0.3048)
			(stroke
				(width 0.1)
				(type default)
			)
			(layer "F.Fab")
		)
		(fp_line
			(start 0.67945 0.3048)
			(end 0.120396 0.3048)
			(stroke
				(width 0.1)
				(type default)
			)
			(layer "F.Fab")
		)
		(fp_line
			(start 0.120396 0.3048)
			(end 0.120396 0.2794)
			(stroke
				(width 0.1)
				(type default)
			)
			(layer "F.Fab")
		)
		(fp_line
			(start -0.12065 0.3048)
			(end -0.67945 0.3048)
			(stroke
				(width 0.1)
				(type default)
			)
			(layer "F.Fab")
		)
		(fp_line
			(start -0.67945 0.3048)
			(end -0.67945 -0.305054)
			(stroke
				(width 0.1)
				(type default)
			)
			(layer "F.Fab")
		)
		(pad "1" smd circle
			(at -0.40005 0 90)
			(size 0 0)
			(layers "F.Cu" "F.Mask" "F.Paste")
			(net "P1V8_AUX")
		)
		(pad "2" smd circle
			(at 0.40005 0 90)
			(size 0 0)
			(layers "F.Cu" "F.Mask" "F.Paste")
			(net "FAB_BMC_REV_ID0")
		)
	)
)
